(kicad_pcb
	(version 20260206)
	(generator "pcbnew")
	(generator_version "10.0")
	(general
		(thickness 1.6)
		(legacy_teardrops no)
	)
	(paper "A4")
	(title_block
		(title "panther-plus-userver — 13130-1b_20150205.brd")
		(comment 1 "Honey Badger (Wiwynn) / footprints 230-237 of 1509")
	)
	(layers
		(0 "F.Cu" signal "TOP")
		(4 "In1.Cu" signal "L2")
		(6 "In2.Cu" signal "L3")
		(8 "In3.Cu" signal "L4")
		(10 "In4.Cu" signal "L5")
		(12 "In5.Cu" signal "L6")
		(14 "In6.Cu" signal "L7")
		(16 "In7.Cu" signal "L8")
		(18 "In8.Cu" signal "L9")
		(20 "In9.Cu" signal "L10")
		(22 "In10.Cu" signal "L11")
		(2 "B.Cu" signal "BOTTOM")
		(9 "F.Adhes" user "F.Adhesive")
		(11 "B.Adhes" user "B.Adhesive")
		(13 "F.Paste" user "Package Geometry/Pastemask Top")
		(15 "B.Paste" user "Package Geometry/Pastemask Bottom")
		(5 "F.SilkS" user "Ref Des/Silkscreen Top")
		(7 "B.SilkS" user "Ref Des/Silkscreen Bottom")
		(1 "F.Mask" user "Board Geometry/Soldermask Top")
		(3 "B.Mask" user "Board Geometry/Soldermask Bottom")
		(17 "Dwgs.User" user "User.Drawings")
		(19 "Cmts.User" user "User.Comments")
		(21 "Eco1.User" user "User.Eco1")
		(23 "Eco2.User" user "User.Eco2")
		(25 "Edge.Cuts" user "Board Geometry/Outline")
		(27 "Margin" user)
		(31 "F.CrtYd" user "Package Geometry/Place Bound Top")
		(29 "B.CrtYd" user "Package Geometry/Place Bound Bottom")
		(35 "F.Fab" user "Ref Des/Assembly Top")
		(33 "B.Fab" user "Ref Des/Assembly Bottom")
	)
	(footprint ""
		(layer "F.Cu")
		(at 45.974 -21.082 180)
		(property "Reference" "C310"
			(at 0 0 180)
			(layer "F.SilkS")
			(hide yes)
			(effects
				(font
					(size 1.27 1.27)
				)
			)
		)
		(property "Value" "SCD1U10V2KX-5GP"
			(at 1.8923 -1.2065 180)
			(unlocked yes)
			(layer "F.Fab")
			(hide yes)
			(effects
				(font
					(size 1.016 1.016)
					(thickness 0.1524)
				)
			)
		)
		(property "Device Type" "C402H22"
			(at 1.8923 -2.7305 180)
			(unlocked yes)
			(layer "F.Fab")
			(hide yes)
			(effects
				(font
					(size 1.016 1.016)
					(thickness 0.1524)
				)
			)
		)
		(duplicate_pad_numbers_are_jumpers no)
		(fp_rect
			(start -0.381 0.7366)
			(end 0.381 -0.7366)
			(stroke
				(width 0)
				(type default)
			)
			(fill no)
			(layer "F.CrtYd")
		)
		(fp_rect
			(start -0.381 0.7366)
			(end 0.381 -0.7366)
			(stroke
				(width 0)
				(type default)
			)
			(fill no)
			(layer "F.Fab")
		)
		(pad "1" smd custom
			(at 0 -0.4572 180)
			(size 0.1143 0.1143)
			(layers "F.Cu" "F.Mask" "F.Paste")
			(net "P3V3_VDD_CLKBUFF")
			(options
				(clearance outline)
				(anchor circle)
			)
			(primitives
				(gr_poly
					(pts
						(arc
							(start -0.254 -0.1778)
							(mid -0.239121 -0.213721)
							(end -0.2032 -0.2286)
						)
						(arc
							(start 0.2032 -0.2286)
							(mid 0.239121 -0.213721)
							(end 0.254 -0.1778)
						)
						(arc
							(start 0.254 0.1778)
							(mid 0.239121 0.213721)
							(end 0.2032 0.2286)
						)
						(arc
							(start -0.2032 0.2286)
							(mid -0.239121 0.213721)
							(end -0.254 0.1778)
						)
					)
					(width 0)
					(fill yes)
				)
			)
		)
		(pad "2" smd custom
			(at 0 0.4572 180)
			(size 0.1143 0.1143)
			(layers "F.Cu" "F.Mask" "F.Paste")
			(net "GND")
			(options
				(clearance outline)
				(anchor circle)
			)
			(primitives
				(gr_poly
					(pts
						(arc
							(start -0.254 -0.1778)
							(mid -0.239121 -0.213721)
							(end -0.2032 -0.2286)
						)
						(arc
							(start 0.2032 -0.2286)
							(mid 0.239121 -0.213721)
							(end 0.254 -0.1778)
						)
						(arc
							(start 0.254 0.1778)
							(mid 0.239121 0.213721)
							(end 0.2032 0.2286)
						)
						(arc
							(start -0.2032 0.2286)
							(mid -0.239121 0.213721)
							(end -0.254 0.1778)
						)
					)
					(width 0)
					(fill yes)
				)
			)
		)
	)
	(footprint ""
		(layer "F.Cu")
		(at 154.94 -13.209778 90)
		(property "Reference" "PR205"
			(at 0 0 90)
			(layer "F.SilkS")
			(hide yes)
			(effects
				(font
					(size 1.27 1.27)
				)
			)
		)
		(property "Value" "0R2J-2-GP"
			(at 1.7907 -1.1176 90)
			(unlocked yes)
			(layer "F.Fab")
			(hide yes)
			(effects
				(font
					(size 1.016 1.016)
					(thickness 0.1524)
				)
			)
		)
		(property "Device Type" "R402H16"
			(at 1.7907 -2.6416 90)
			(unlocked yes)
			(layer "F.Fab")
			(hide yes)
			(effects
				(font
					(size 1.016 1.016)
					(thickness 0.1524)
				)
			)
		)
		(duplicate_pad_numbers_are_jumpers no)
		(fp_rect
			(start -0.381 0.8382)
			(end 0.381 -0.8382)
			(stroke
				(width 0)
				(type default)
			)
			(fill no)
			(layer "F.CrtYd")
		)
		(fp_rect
			(start -0.381 0.8382)
			(end 0.381 -0.8382)
			(stroke
				(width 0)
				(type default)
			)
			(fill no)
			(layer "F.Fab")
		)
		(pad "1" smd custom
			(at 0 -0.4318 90)
			(size 0.127 0.127)
			(layers "F.Cu" "F.Mask" "F.Paste")
			(net "VSENSE_PVDDR_A_VRTN")
			(options
				(clearance outline)
				(anchor circle)
			)
			(primitives
				(gr_poly
					(pts
						(arc
							(start -0.2032 -0.2794)
							(mid -0.239121 -0.264521)
							(end -0.254 -0.2286)
						)
						(arc
							(start -0.254 0.2286)
							(mid -0.239121 0.264521)
							(end -0.2032 0.2794)
						)
						(arc
							(start 0.2032 0.2794)
							(mid 0.239121 0.264521)
							(end 0.254 0.2286)
						)
						(arc
							(start 0.254 -0.2286)
							(mid 0.239121 -0.264521)
							(end 0.2032 -0.2794)
						)
					)
					(width 0)
					(fill yes)
				)
			)
		)
		(pad "2" smd custom
			(at 0 0.4318 90)
			(size 0.127 0.127)
			(layers "F.Cu" "F.Mask" "F.Paste")
			(net "GND")
			(options
				(clearance outline)
				(anchor circle)
			)
			(primitives
				(gr_poly
					(pts
						(arc
							(start -0.2032 -0.2794)
							(mid -0.239121 -0.264521)
							(end -0.254 -0.2286)
						)
						(arc
							(start -0.254 0.2286)
							(mid -0.239121 0.264521)
							(end -0.2032 0.2794)
						)
						(arc
							(start 0.2032 0.2794)
							(mid 0.239121 0.264521)
							(end 0.254 0.2286)
						)
						(arc
							(start 0.254 -0.2286)
							(mid 0.239121 -0.264521)
							(end 0.2032 -0.2794)
						)
					)
					(width 0)
					(fill yes)
				)
			)
		)
	)
	(footprint ""
		(layer "F.Cu")
		(at 188.9506 -28.2194 90)
		(property "Reference" "PR211"
			(at 0 0 90)
			(layer "F.SilkS")
			(hide yes)
			(effects
				(font
					(size 1.27 1.27)
				)
			)
		)
		(property "Value" "100R2F-L1-GP-U"
			(at 1.7907 -1.1176 90)
			(unlocked yes)
			(layer "F.Fab")
			(hide yes)
			(effects
				(font
					(size 1.016 1.016)
					(thickness 0.1524)
				)
			)
		)
		(property "Device Type" "R402H14"
			(at 1.7907 -2.6416 90)
			(unlocked yes)
			(layer "F.Fab")
			(hide yes)
			(effects
				(font
					(size 1.016 1.016)
					(thickness 0.1524)
				)
			)
		)
		(duplicate_pad_numbers_are_jumpers no)
		(fp_rect
			(start -0.381 0.8382)
			(end 0.381 -0.8382)
			(stroke
				(width 0)
				(type default)
			)
			(fill no)
			(layer "F.CrtYd")
		)
		(fp_rect
			(start -0.381 0.8382)
			(end 0.381 -0.8382)
			(stroke
				(width 0)
				(type default)
			)
			(fill no)
			(layer "F.Fab")
		)
		(pad "1" smd custom
			(at 0 -0.4318 90)
			(size 0.127 0.127)
			(layers "F.Cu" "F.Mask" "F.Paste")
			(net "VR_PVDDR_A_SUMN")
			(options
				(clearance outline)
				(anchor circle)
			)
			(primitives
				(gr_poly
					(pts
						(arc
							(start -0.2032 -0.2794)
							(mid -0.239121 -0.264521)
							(end -0.254 -0.2286)
						)
						(arc
							(start -0.254 0.2286)
							(mid -0.239121 0.264521)
							(end -0.2032 0.2794)
						)
						(arc
							(start 0.2032 0.2794)
							(mid 0.239121 0.264521)
							(end 0.254 0.2286)
						)
						(arc
							(start 0.254 -0.2286)
							(mid 0.239121 -0.264521)
							(end 0.2032 -0.2794)
						)
					)
					(width 0)
					(fill yes)
				)
			)
		)
		(pad "2" smd custom
			(at 0 0.4318 90)
			(size 0.127 0.127)
			(layers "F.Cu" "F.Mask" "F.Paste")
			(net "VR_PVDDRA_ISUMN1")
			(options
				(clearance outline)
				(anchor circle)
			)
			(primitives
				(gr_poly
					(pts
						(arc
							(start -0.2032 -0.2794)
							(mid -0.239121 -0.264521)
							(end -0.254 -0.2286)
						)
						(arc
							(start -0.254 0.2286)
							(mid -0.239121 0.264521)
							(end -0.2032 0.2794)
						)
						(arc
							(start 0.2032 0.2794)
							(mid 0.239121 0.264521)
							(end 0.254 0.2286)
						)
						(arc
							(start 0.254 -0.2286)
							(mid 0.239121 -0.264521)
							(end 0.2032 -0.2794)
						)
					)
					(width 0)
					(fill yes)
				)
			)
		)
	)
	(footprint ""
		(layer "F.Cu")
		(at 164.719 -42.418 180)
		(property "Reference" "C21"
			(at 0 0 180)
			(layer "F.SilkS")
			(hide yes)
			(effects
				(font
					(size 1.27 1.27)
				)
			)
		)
		(property "Value" "SCD1U10V2KX-5GP"
			(at 1.1811 -2.7051 180)
			(unlocked yes)
			(layer "F.Fab")
			(hide yes)
			(effects
				(font
					(size 1.016 1.016)
					(thickness 0.1524)
				)
			)
		)
		(property "Device Type" "C402H22"
			(at 1.1811 -4.2291 180)
			(unlocked yes)
			(layer "F.Fab")
			(hide yes)
			(effects
				(font
					(size 1.016 1.016)
					(thickness 0.1524)
				)
			)
		)
		(duplicate_pad_numbers_are_jumpers no)
		(fp_rect
			(start -0.381 0.7366)
			(end 0.381 -0.7366)
			(stroke
				(width 0)
				(type default)
			)
			(fill no)
			(layer "F.CrtYd")
		)
		(fp_rect
			(start -0.381 0.7366)
			(end 0.381 -0.7366)
			(stroke
				(width 0)
				(type default)
			)
			(fill no)
			(layer "F.Fab")
		)
		(pad "1" smd custom
			(at 0 -0.4572 180)
			(size 0.1143 0.1143)
			(layers "F.Cu" "F.Mask" "F.Paste")
			(net "GND")
			(options
				(clearance outline)
				(anchor circle)
			)
			(primitives
				(gr_poly
					(pts
						(arc
							(start -0.254 -0.1778)
							(mid -0.239121 -0.213721)
							(end -0.2032 -0.2286)
						)
						(arc
							(start 0.2032 -0.2286)
							(mid 0.239121 -0.213721)
							(end 0.254 -0.1778)
						)
						(arc
							(start 0.254 0.1778)
							(mid 0.239121 0.213721)
							(end 0.2032 0.2286)
						)
						(arc
							(start -0.2032 0.2286)
							(mid -0.239121 0.213721)
							(end -0.254 0.1778)
						)
					)
					(width 0)
					(fill yes)
				)
			)
		)
		(pad "2" smd custom
			(at 0 0.4572 180)
			(size 0.1143 0.1143)
			(layers "F.Cu" "F.Mask" "F.Paste")
			(net "P3V3_STBY")
			(options
				(clearance outline)
				(anchor circle)
			)
			(primitives
				(gr_poly
					(pts
						(arc
							(start -0.254 -0.1778)
							(mid -0.239121 -0.213721)
							(end -0.2032 -0.2286)
						)
						(arc
							(start 0.2032 -0.2286)
							(mid 0.239121 -0.213721)
							(end 0.254 -0.1778)
						)
						(arc
							(start 0.254 0.1778)
							(mid 0.239121 0.213721)
							(end 0.2032 0.2286)
						)
						(arc
							(start -0.2032 0.2286)
							(mid -0.239121 0.213721)
							(end -0.254 0.1778)
						)
					)
					(width 0)
					(fill yes)
				)
			)
		)
	)
	(footprint ""
		(layer "F.Cu")
		(at 28.9179 -38.862 -90)
		(property "Reference" "PR191"
			(at 0 0 270)
			(layer "F.SilkS")
			(hide yes)
			(effects
				(font
					(size 1.27 1.27)
				)
			)
		)
		(property "Value" "0R6J-3-GP"
			(at 0.0127 -3.2766 270)
			(unlocked yes)
			(layer "F.Fab")
			(hide yes)
			(effects
				(font
					(size 1.016 1.016)
					(thickness 0.1524)
				)
			)
		)
		(property "Device Type" "R1206H28"
			(at 0.0127 -4.8006 270)
			(unlocked yes)
			(layer "F.Fab")
			(hide yes)
			(effects
				(font
					(size 1.016 1.016)
					(thickness 0.1524)
				)
			)
		)
		(duplicate_pad_numbers_are_jumpers no)
		(fp_line
			(start -0.7239 0.381)
			(end 0.7239 0.381)
			(stroke
				(width 0.1524)
				(type default)
			)
			(layer "F.SilkS")
		)
		(fp_line
			(start 0.7239 0.381)
			(end 0.7239 -0.381)
			(stroke
				(width 0.1524)
				(type default)
			)
			(layer "F.SilkS")
		)
		(fp_line
			(start -0.7239 -0.381)
			(end -0.7239 0.381)
			(stroke
				(width 0.1524)
				(type default)
			)
			(layer "F.SilkS")
		)
		(fp_line
			(start 0.7239 -0.381)
			(end -0.7239 -0.381)
			(stroke
				(width 0.1524)
				(type default)
			)
			(layer "F.SilkS")
		)
		(fp_poly
			(pts
				(xy -0.7239 0.381) (xy 0.7239 0.381) (xy 0.7239 -0.381) (xy -0.7239 -0.381)
			)
			(stroke
				(width 0)
				(type default)
			)
			(fill yes)
			(layer "F.SilkS")
		)
		(fp_rect
			(start -1.0541 1.9812)
			(end 1.0541 -1.9812)
			(stroke
				(width 0)
				(type default)
			)
			(fill no)
			(layer "F.CrtYd")
		)
		(fp_rect
			(start -1.0541 1.9812)
			(end 1.0541 -1.9812)
			(stroke
				(width 0)
				(type default)
			)
			(fill no)
			(layer "F.Fab")
		)
		(pad "1" smd rect
			(at 0 -1.3462 270)
			(size 1.8542 1.016)
			(layers "F.Cu" "F.Mask" "F.Paste")
			(net "P3V3_STBY")
		)
		(pad "2" smd rect
			(at 0 1.3462 270)
			(size 1.8542 1.016)
			(layers "F.Cu" "F.Mask" "F.Paste")
			(net "P3V3_STBY_OUT")
		)
	)
	(footprint ""
		(layer "F.Cu")
		(at 137.40384 -56.46039 90)
		(property "Reference" "PU4"
			(at 0 0 90)
			(layer "F.SilkS")
			(hide yes)
			(effects
				(font
					(size 1.27 1.27)
				)
			)
		)
		(property "Value" "TPS51200-GP-U1"
			(at 2.9083 1.397 90)
			(unlocked yes)
			(layer "F.Fab")
			(hide yes)
			(effects
				(font
					(size 1.016 1.016)
					(thickness 0.1524)
				)
			)
		)
		(property "Device Type" "QFN10-G4H40"
			(at 2.9083 -0.127 90)
			(unlocked yes)
			(layer "F.Fab")
			(hide yes)
			(effects
				(font
					(size 1.016 1.016)
					(thickness 0.1524)
				)
			)
		)
		(duplicate_pad_numbers_are_jumpers no)
		(fp_poly
			(pts
				(xy 1.0287 -2.0066) (xy 1.27 -2.2479) (xy 0.7874 -2.2479)
			)
			(stroke
				(width 0)
				(type default)
			)
			(fill yes)
			(layer "F.SilkS")
		)
		(fp_rect
			(start -1.7526 2.0066)
			(end 1.7526 -2.0066)
			(stroke
				(width 0)
				(type default)
			)
			(fill no)
			(layer "F.CrtYd")
		)
		(fp_rect
			(start -1.7526 2.0066)
			(end 1.7526 -2.0066)
			(stroke
				(width 0)
				(type default)
			)
			(fill no)
			(layer "F.Fab")
		)
		(pad "1" smd rect
			(at 0.999998 -1.4605 90)
			(size 0.3048 0.8382)
			(layers "F.Cu" "F.Mask" "F.Paste")
			(net "PV_VTT_DDR_REFIN")
		)
		(pad "2" smd rect
			(at 0.500126 -1.4605 90)
			(size 0.3048 0.8382)
			(layers "F.Cu" "F.Mask" "F.Paste")
			(net "PV_VDDR")
		)
		(pad "3" smd rect
			(at 0 -1.4605 90)
			(size 0.3048 0.8382)
			(layers "F.Cu" "F.Mask" "F.Paste")
			(net "PV_VTT_DDR_A")
		)
		(pad "4" smd rect
			(at -0.500126 -1.4605 90)
			(size 0.3048 0.8382)
			(layers "F.Cu" "F.Mask" "F.Paste")
			(net "GND")
		)
		(pad "5" smd rect
			(at -0.999998 -1.4605 90)
			(size 0.3048 0.8382)
			(layers "F.Cu" "F.Mask" "F.Paste")
			(net "PV_VTT_DDR_SNS")
		)
		(pad "6" smd rect
			(at -0.999998 1.4605 90)
			(size 0.3048 0.8382)
			(layers "F.Cu" "F.Mask" "F.Paste")
			(net "PV_VTT_DDR_REFO")
		)
		(pad "7" smd rect
			(at -0.500126 1.4605 90)
			(size 0.3048 0.8382)
			(layers "F.Cu" "F.Mask" "F.Paste")
			(net "PV_VTT_DDR_EN")
		)
		(pad "8" smd rect
			(at 0 1.4605 90)
			(size 0.3048 0.8382)
			(layers "F.Cu" "F.Mask" "F.Paste")
			(net "GND")
		)
		(pad "9" smd rect
			(at 0.500126 1.4605 90)
			(size 0.3048 0.8382)
			(layers "F.Cu" "F.Mask" "F.Paste")
			(net "PV_VTT_DDR_R_PG")
		)
		(pad "10" smd rect
			(at 0.999998 1.4605 90)
			(size 0.3048 0.8382)
			(layers "F.Cu" "F.Mask" "F.Paste")
			(net "PV_VTT_DDR_VIN")
		)
		(pad "11" smd rect
			(at 0 0 90)
			(size 2.9972 1.6764)
			(layers "F.Cu" "F.Mask" "F.Paste")
			(net "GND")
		)
	)
	(footprint ""
		(layer "F.Cu")
		(at 33.401 -13.081)
		(property "Reference" "R422"
			(at 0 0 0)
			(layer "F.SilkS")
			(hide yes)
			(effects
				(font
					(size 1.27 1.27)
				)
			)
		)
		(property "Value" "0R2J-2-GP"
			(at 1.7907 -1.1176 0)
			(unlocked yes)
			(layer "F.Fab")
			(hide yes)
			(effects
				(font
					(size 1.016 1.016)
					(thickness 0.1524)
				)
			)
		)
		(property "Device Type" "R402H16"
			(at 1.7907 -2.6416 0)
			(unlocked yes)
			(layer "F.Fab")
			(hide yes)
			(effects
				(font
					(size 1.016 1.016)
					(thickness 0.1524)
				)
			)
		)
		(duplicate_pad_numbers_are_jumpers no)
		(fp_rect
			(start -0.381 0.8382)
			(end 0.381 -0.8382)
			(stroke
				(width 0)
				(type default)
			)
			(fill no)
			(layer "F.CrtYd")
		)
		(fp_rect
			(start -0.381 0.8382)
			(end 0.381 -0.8382)
			(stroke
				(width 0)
				(type default)
			)
			(fill no)
			(layer "F.Fab")
		)
		(pad "1" smd custom
			(at 0 -0.4318)
			(size 0.127 0.127)
			(layers "F.Cu" "F.Mask" "F.Paste")
			(net "BMC_I2C_DATA")
			(options
				(clearance outline)
				(anchor circle)
			)
			(primitives
				(gr_poly
					(pts
						(arc
							(start -0.2032 -0.2794)
							(mid -0.239121 -0.264521)
							(end -0.254 -0.2286)
						)
						(arc
							(start -0.254 0.2286)
							(mid -0.239121 0.264521)
							(end -0.2032 0.2794)
						)
						(arc
							(start 0.2032 0.2794)
							(mid 0.239121 0.264521)
							(end 0.254 0.2286)
						)
						(arc
							(start 0.254 -0.2286)
							(mid 0.239121 -0.264521)
							(end 0.2032 -0.2794)
						)
					)
					(width 0)
					(fill yes)
				)
			)
		)
		(pad "2" smd custom
			(at 0 0.4318)
			(size 0.127 0.127)
			(layers "F.Cu" "F.Mask" "F.Paste")
			(net "PCIE_GF_I2C_DATA")
			(options
				(clearance outline)
				(anchor circle)
			)
			(primitives
				(gr_poly
					(pts
						(arc
							(start -0.2032 -0.2794)
							(mid -0.239121 -0.264521)
							(end -0.254 -0.2286)
						)
						(arc
							(start -0.254 0.2286)
							(mid -0.239121 0.264521)
							(end -0.2032 0.2794)
						)
						(arc
							(start 0.2032 0.2794)
							(mid 0.239121 0.264521)
							(end 0.254 0.2286)
						)
						(arc
							(start 0.254 -0.2286)
							(mid 0.239121 -0.264521)
							(end 0.2032 -0.2794)
						)
					)
					(width 0)
					(fill yes)
				)
			)
		)
	)
	(footprint ""
		(layer "F.Cu")
		(at 38.354 -39.116)
		(property "Reference" "R249"
			(at 0 0 0)
			(layer "F.SilkS")
			(hide yes)
			(effects
				(font
					(size 1.27 1.27)
				)
			)
		)
		(property "Value" "0R2J-2-GP"
			(at 0.064008 -3.993896 0)
			(unlocked yes)
			(layer "F.Fab")
			(hide yes)
			(effects
				(font
					(size 1.016 1.016)
					(thickness 0.1524)
				)
			)
		)
		(property "Device Type" "R402H16"
			(at 0.064008 -5.517896 0)
			(unlocked yes)
			(layer "F.Fab")
			(hide yes)
			(effects
				(font
					(size 1.016 1.016)
					(thickness 0.1524)
				)
			)
		)
		(duplicate_pad_numbers_are_jumpers no)
		(fp_rect
			(start -0.381 0.8382)
			(end 0.381 -0.8382)
			(stroke
				(width 0)
				(type default)
			)
			(fill no)
			(layer "F.CrtYd")
		)
		(fp_rect
			(start -0.381 0.8382)
			(end 0.381 -0.8382)
			(stroke
				(width 0)
				(type default)
			)
			(fill no)
			(layer "F.Fab")
		)
		(pad "1" smd custom
			(at 0 -0.4318)
			(size 0.127 0.127)
			(layers "F.Cu" "F.Mask" "F.Paste")
			(net "SMBUS_HOST_CLK")
			(options
				(clearance outline)
				(anchor circle)
			)
			(primitives
				(gr_poly
					(pts
						(arc
							(start -0.2032 -0.2794)
							(mid -0.239121 -0.264521)
							(end -0.254 -0.2286)
						)
						(arc
							(start -0.254 0.2286)
							(mid -0.239121 0.264521)
							(end -0.2032 0.2794)
						)
						(arc
							(start 0.2032 0.2794)
							(mid 0.239121 0.264521)
							(end 0.254 0.2286)
						)
						(arc
							(start 0.254 -0.2286)
							(mid 0.239121 -0.264521)
							(end 0.2032 -0.2794)
						)
					)
					(width 0)
					(fill yes)
				)
			)
		)
		(pad "2" smd custom
			(at 0 0.4318)
			(size 0.127 0.127)
			(layers "F.Cu" "F.Mask" "F.Paste")
			(net "SMB_XDP_CLK_R")
			(options
				(clearance outline)
				(anchor circle)
			)
			(primitives
				(gr_poly
					(pts
						(arc
							(start -0.2032 -0.2794)
							(mid -0.239121 -0.264521)
							(end -0.254 -0.2286)
						)
						(arc
							(start -0.254 0.2286)
							(mid -0.239121 0.264521)
							(end -0.2032 0.2794)
						)
						(arc
							(start 0.2032 0.2794)
							(mid 0.239121 0.264521)
							(end 0.254 0.2286)
						)
						(arc
							(start 0.254 -0.2286)
							(mid 0.239121 -0.264521)
							(end 0.2032 -0.2794)
						)
					)
					(width 0)
					(fill yes)
				)
			)
		)
	)
)
